# S9S_MB_2U (Grand Teton) — schematic netlist excerpt (pin names and nets, part order shuffled) for the footprints in the layout excerpt that follows; sources: Cadence DE-HDL packaged netlist, KiCad conversion of 03242023_DA0F0TMBIJ0_F0T_Motherboard_J_brd_V01_OCP.brd

R1485  Q_RES  200 1% EMPTY  pkg 0402LF  page 182 : A = PVNN_TERM_CPU0 ; B = FM_PCH_TRIGGER0_R_N
R1960  Q_RES  0 5% CHIP  pkg 0402LF  page 14 : A = H_CPU0_PMSYNC_PCH_R2 ; B = H_CPU0_PMSYNC_PCH_R

(kicad_pcb
	(version 20260206)
	(generator "pcbnew")
	(generator_version "10.0")
	(general
		(thickness 1.6)
		(legacy_teardrops no)
	)
	(paper "A4")
	(title_block
		(title "03242023_DA0F0TMBIJ0_F0T_Motherboard_J_brd_V01_OCP.brd")
		(comment 1 "Grand Teton / footprints 5238-5239 of 6105")
	)
	(layers
		(0 "F.Cu" signal "TOP")
		(4 "In1.Cu" signal "GND")
		(6 "In2.Cu" signal "IN1")
		(8 "In3.Cu" signal "GND1")
		(10 "In4.Cu" signal "IN2")
		(12 "In5.Cu" signal "GND2")
		(14 "In6.Cu" signal "IN3")
		(16 "In7.Cu" signal "GND3")
		(18 "In8.Cu" signal "VCC")
		(20 "In9.Cu" signal "VCC1")
		(22 "In10.Cu" signal "GND4")
		(24 "In11.Cu" signal "IN4")
		(26 "In12.Cu" signal "GND5")
		(28 "In13.Cu" signal "IN5")
		(30 "In14.Cu" signal "GND6")
		(32 "In15.Cu" signal "IN6")
		(34 "In16.Cu" signal "GND7")
		(2 "B.Cu" signal "BOTTOM")
		(9 "F.Adhes" user "F.Adhesive")
		(11 "B.Adhes" user "B.Adhesive")
		(13 "F.Paste" user "Package Geometry/Pastemask Top")
		(15 "B.Paste" user "Package Geometry/Pastemask Bottom")
		(5 "F.SilkS" user "Ref Des/Silkscreen Top")
		(7 "B.SilkS" user "Ref Des/Silkscreen Bottom")
		(1 "F.Mask" user "Board Geometry/Soldermask Top")
		(3 "B.Mask" user "Board Geometry/Soldermask Bottom")
		(17 "Dwgs.User" user "User.Drawings")
		(19 "Cmts.User" user "User.Comments")
		(21 "Eco1.User" user "User.Eco1")
		(23 "Eco2.User" user "User.Eco2")
		(25 "Edge.Cuts" user "Board Geometry/Outline")
		(27 "Margin" user)
		(31 "F.CrtYd" user "Package Geometry/Place Bound Top")
		(29 "B.CrtYd" user "Package Geometry/Place Bound Bottom")
		(35 "F.Fab" user "Ref Des/Assembly Top")
		(33 "B.Fab" user "Ref Des/Assembly Bottom")
	)
	(footprint ""
		(layer "B.Cu")
		(at 322.984622 -58.283348 180)
		(property "Reference" "R1485"
			(at 0 0 0)
			(layer "B.SilkS")
			(hide yes)
			(effects
				(font
					(size 1.27 1.27)
				)
				(justify mirror)
			)
		)
		(property "Value" ""
			(at 0 0 0)
			(layer "B.Fab")
			(effects
				(font
					(size 1.27 1.27)
				)
				(justify mirror)
			)
		)
		(duplicate_pad_numbers_are_jumpers no)
		(fp_line
			(start 0.7874 0.4064)
			(end 0.7874 -0.4064)
			(stroke
				(width 0.1524)
				(type default)
			)
			(layer "B.SilkS")
		)
		(fp_line
			(start 0.7874 -0.4064)
			(end -0.7874 -0.4064)
			(stroke
				(width 0.1524)
				(type default)
			)
			(layer "B.SilkS")
		)
		(fp_line
			(start -0.7874 0.4064)
			(end 0.7874 0.4064)
			(stroke
				(width 0.1524)
				(type default)
			)
			(layer "B.SilkS")
		)
		(fp_line
			(start -0.7874 -0.4064)
			(end -0.7874 0.4064)
			(stroke
				(width 0.1524)
				(type default)
			)
			(layer "B.SilkS")
		)
		(fp_line
			(start 0.67945 0.3048)
			(end 0.67945 -0.305054)
			(stroke
				(width 0.1)
				(type default)
			)
			(layer "B.Fab")
		)
		(fp_line
			(start 0.67945 -0.305054)
			(end 0.12065 -0.305054)
			(stroke
				(width 0.1)
				(type default)
			)
			(layer "B.Fab")
		)
		(fp_line
			(start 0.12065 0.3048)
			(end 0.67945 0.3048)
			(stroke
				(width 0.1)
				(type default)
			)
			(layer "B.Fab")
		)
		(fp_line
			(start 0.12065 0.2794)
			(end 0.12065 0.3048)
			(stroke
				(width 0.1)
				(type default)
			)
			(layer "B.Fab")
		)
		(fp_line
			(start 0.12065 -0.2794)
			(end -0.12065 -0.2794)
			(stroke
				(width 0.1)
				(type default)
			)
			(layer "B.Fab")
		)
		(fp_line
			(start 0.12065 -0.305054)
			(end 0.12065 -0.2794)
			(stroke
				(width 0.1)
				(type default)
			)
			(layer "B.Fab")
		)
		(fp_line
			(start -0.120396 0.3048)
			(end -0.120396 0.2794)
			(stroke
				(width 0.1)
				(type default)
			)
			(layer "B.Fab")
		)
		(fp_line
			(start -0.120396 0.2794)
			(end 0.12065 0.2794)
			(stroke
				(width 0.1)
				(type default)
			)
			(layer "B.Fab")
		)
		(fp_line
			(start -0.12065 -0.2794)
			(end -0.12065 -0.3048)
			(stroke
				(width 0.1)
				(type default)
			)
			(layer "B.Fab")
		)
		(fp_line
			(start -0.12065 -0.3048)
			(end -0.67945 -0.3048)
			(stroke
				(width 0.1)
				(type default)
			)
			(layer "B.Fab")
		)
		(fp_line
			(start -0.67945 0.3048)
			(end -0.120396 0.3048)
			(stroke
				(width 0.1)
				(type default)
			)
			(layer "B.Fab")
		)
		(fp_line
			(start -0.67945 -0.3048)
			(end -0.67945 0.3048)
			(stroke
				(width 0.1)
				(type default)
			)
			(layer "B.Fab")
		)
		(pad "1" smd circle
			(at 0.40005 0)
			(size 0 0)
			(layers "B.Cu" "B.Mask" "B.Paste")
			(net "PVNN_TERM_CPU0")
		)
		(pad "2" smd circle
			(at -0.40005 0)
			(size 0 0)
			(layers "B.Cu" "B.Mask" "B.Paste")
			(net "FM_PCH_TRIGGER0_R_N")
		)
	)
	(footprint ""
		(layer "B.Cu")
		(at 326.205342 -48.358298)
		(property "Reference" "R1960"
			(at 0 0 0)
			(layer "B.SilkS")
			(hide yes)
			(effects
				(font
					(size 1.27 1.27)
				)
				(justify mirror)
			)
		)
		(property "Value" ""
			(at 0 0 0)
			(layer "B.Fab")
			(effects
				(font
					(size 1.27 1.27)
				)
				(justify mirror)
			)
		)
		(duplicate_pad_numbers_are_jumpers no)
		(fp_line
			(start -0.7874 -0.4064)
			(end -0.7874 0.4064)
			(stroke
				(width 0.1524)
				(type default)
			)
			(layer "B.SilkS")
		)
		(fp_line
			(start -0.7874 0.4064)
			(end 0.7874 0.4064)
			(stroke
				(width 0.1524)
				(type default)
			)
			(layer "B.SilkS")
		)
		(fp_line
			(start 0.7874 -0.4064)
			(end -0.7874 -0.4064)
			(stroke
				(width 0.1524)
				(type default)
			)
			(layer "B.SilkS")
		)
		(fp_line
			(start 0.7874 0.4064)
			(end 0.7874 -0.4064)
			(stroke
				(width 0.1524)
				(type default)
			)
			(layer "B.SilkS")
		)
		(fp_line
			(start -0.67945 -0.3048)
			(end -0.67945 0.3048)
			(stroke
				(width 0.1)
				(type default)
			)
			(layer "B.Fab")
		)
		(fp_line
			(start -0.67945 0.3048)
			(end -0.120396 0.3048)
			(stroke
				(width 0.1)
				(type default)
			)
			(layer "B.Fab")
		)
		(fp_line
			(start -0.12065 -0.3048)
			(end -0.67945 -0.3048)
			(stroke
				(width 0.1)
				(type default)
			)
			(layer "B.Fab")
		)
		(fp_line
			(start -0.12065 -0.2794)
			(end -0.12065 -0.3048)
			(stroke
				(width 0.1)
				(type default)
			)
			(layer "B.Fab")
		)
		(fp_line
			(start -0.120396 0.2794)
			(end 0.12065 0.2794)
			(stroke
				(width 0.1)
				(type default)
			)
			(layer "B.Fab")
		)
		(fp_line
			(start -0.120396 0.3048)
			(end -0.120396 0.2794)
			(stroke
				(width 0.1)
				(type default)
			)
			(layer "B.Fab")
		)
		(fp_line
			(start 0.12065 -0.305054)
			(end 0.12065 -0.2794)
			(stroke
				(width 0.1)
				(type default)
			)
			(layer "B.Fab")
		)
		(fp_line
			(start 0.12065 -0.2794)
			(end -0.12065 -0.2794)
			(stroke
				(width 0.1)
				(type default)
			)
			(layer "B.Fab")
		)
		(fp_line
			(start 0.12065 0.2794)
			(end 0.12065 0.3048)
			(stroke
				(width 0.1)
				(type default)
			)
			(layer "B.Fab")
		)
		(fp_line
			(start 0.12065 0.3048)
			(end 0.67945 0.3048)
			(stroke
				(width 0.1)
				(type default)
			)
			(layer "B.Fab")
		)
		(fp_line
			(start 0.67945 -0.305054)
			(end 0.12065 -0.305054)
			(stroke
				(width 0.1)
				(type default)
			)
			(layer "B.Fab")
		)
		(fp_line
			(start 0.67945 0.3048)
			(end 0.67945 -0.305054)
			(stroke
				(width 0.1)
				(type default)
			)
			(layer "B.Fab")
		)
		(pad "1" smd circle
			(at 0.40005 0 180)
			(size 0 0)
			(layers "B.Cu" "B.Mask" "B.Paste")
			(net "H_CPU0_PMSYNC_PCH_R2")
		)
		(pad "2" smd circle
			(at -0.40005 0 180)
			(size 0 0)
			(layers "B.Cu" "B.Mask" "B.Paste")
			(net "H_CPU0_PMSYNC_PCH_R")
		)
	)
)
